(kicad_pcb
	(version 20260206)
	(generator "pcbnew")
	(generator_version "10.0")
	(general
		(thickness 1.6)
		(legacy_teardrops no)
	)
	(paper "A4")
	(title_block
		(title "baseboard — 13948-1b.1110WZS1818.brd")
		(comment 1 "Honey Badger (Wiwynn) / footprints 2326-2333 of 2523")
	)
	(layers
		(0 "F.Cu" signal "TOP")
		(4 "In1.Cu" signal "L2GND")
		(6 "In2.Cu" signal "L3")
		(8 "In3.Cu" signal "L4VCC")
		(10 "In4.Cu" signal "L5VCC")
		(12 "In5.Cu" signal "L6")
		(14 "In6.Cu" signal "L7GND")
		(2 "B.Cu" signal "BOTTOM")
		(9 "F.Adhes" user "F.Adhesive")
		(11 "B.Adhes" user "B.Adhesive")
		(13 "F.Paste" user "Package Geometry/Pastemask Top")
		(15 "B.Paste" user "Package Geometry/Pastemask Bottom")
		(5 "F.SilkS" user "Ref Des/Silkscreen Top")
		(7 "B.SilkS" user "Ref Des/Silkscreen Bottom")
		(1 "F.Mask" user "Board Geometry/Soldermask Top")
		(3 "B.Mask" user "Board Geometry/Soldermask Bottom")
		(17 "Dwgs.User" user "User.Drawings")
		(19 "Cmts.User" user "User.Comments")
		(21 "Eco1.User" user "User.Eco1")
		(23 "Eco2.User" user "User.Eco2")
		(25 "Edge.Cuts" user "Board Geometry/Outline")
		(27 "Margin" user)
		(31 "F.CrtYd" user "Package Geometry/Place Bound Top")
		(29 "B.CrtYd" user "Package Geometry/Place Bound Bottom")
		(35 "F.Fab" user "Ref Des/Assembly Top")
		(33 "B.Fab" user "Ref Des/Assembly Bottom")
	)
	(footprint ""
		(layer "B.Cu")
		(at 328.295 -105.41)
		(property "Reference" "PR26"
			(at 0 0 0)
			(layer "B.SilkS")
			(hide yes)
			(effects
				(font
					(size 1.27 1.27)
				)
				(justify mirror)
			)
		)
		(property "Value" "3K9R2F-GP"
			(at -0.064008 -3.993896 0)
			(unlocked yes)
			(layer "B.Fab")
			(hide yes)
			(effects
				(font
					(size 1.016 1.016)
					(thickness 0.1524)
				)
				(justify mirror)
			)
		)
		(property "Device Type" "R402H16"
			(at -0.064008 -5.517896 0)
			(unlocked yes)
			(layer "B.Fab")
			(hide yes)
			(effects
				(font
					(size 1.016 1.016)
					(thickness 0.1524)
				)
				(justify mirror)
			)
		)
		(duplicate_pad_numbers_are_jumpers no)
		(fp_line
			(start -0.508 -0.9398)
			(end 0.508 -0.9398)
			(stroke
				(width 0.1524)
				(type default)
			)
			(layer "B.SilkS")
		)
		(fp_line
			(start 0.508 -0.9398)
			(end 0.508 0.9398)
			(stroke
				(width 0.1524)
				(type default)
			)
			(layer "B.SilkS")
		)
		(fp_rect
			(start 0.508 0.9398)
			(end -0.508 -0.9398)
			(stroke
				(width 0)
				(type default)
			)
			(fill no)
			(layer "B.CrtYd")
		)
		(fp_rect
			(start 0.508 0.9398)
			(end -0.508 -0.9398)
			(stroke
				(width 0)
				(type default)
			)
			(fill no)
			(layer "B.Fab")
		)
		(pad "1" smd custom
			(at 0 -0.4445 180)
			(size 0.1397 0.1397)
			(layers "B.Cu" "B.Mask" "B.Paste")
			(net "P3V3_STBY_LL")
			(options
				(clearance outline)
				(anchor circle)
			)
			(primitives
				(gr_poly
					(pts
						(arc
							(start -0.1778 0.2794)
							(mid -0.249642 0.249642)
							(end -0.2794 0.1778)
						)
						(arc
							(start -0.2794 -0.1778)
							(mid -0.249642 -0.249642)
							(end -0.1778 -0.2794)
						)
						(arc
							(start 0.1778 -0.2794)
							(mid 0.249642 -0.249642)
							(end 0.2794 -0.1778)
						)
						(arc
							(start 0.2794 0.1778)
							(mid 0.249642 0.249642)
							(end 0.1778 0.2794)
						)
					)
					(width 0)
					(fill yes)
				)
			)
		)
		(pad "2" smd custom
			(at 0 0.4445 180)
			(size 0.1397 0.1397)
			(layers "B.Cu" "B.Mask" "B.Paste")
			(net "P3V3_STBY_LL_R")
			(options
				(clearance outline)
				(anchor circle)
			)
			(primitives
				(gr_poly
					(pts
						(arc
							(start -0.1778 0.2794)
							(mid -0.249642 0.249642)
							(end -0.2794 0.1778)
						)
						(arc
							(start -0.2794 -0.1778)
							(mid -0.249642 -0.249642)
							(end -0.1778 -0.2794)
						)
						(arc
							(start 0.1778 -0.2794)
							(mid 0.249642 -0.249642)
							(end 0.2794 -0.1778)
						)
						(arc
							(start 0.2794 0.1778)
							(mid 0.249642 0.249642)
							(end 0.1778 0.2794)
						)
					)
					(width 0)
					(fill yes)
				)
			)
		)
	)
	(footprint ""
		(layer "B.Cu")
		(at 274.193 -162.56 -90)
		(property "Reference" "R327"
			(at 0 0 90)
			(layer "B.SilkS")
			(hide yes)
			(effects
				(font
					(size 1.27 1.27)
				)
				(justify mirror)
			)
		)
		(property "Value" "100KR2F-L1-GP"
			(at -0.064008 -3.993896 270)
			(unlocked yes)
			(layer "B.Fab")
			(hide yes)
			(effects
				(font
					(size 1.016 1.016)
					(thickness 0.1524)
				)
				(justify mirror)
			)
		)
		(property "Device Type" "R402H16"
			(at -0.064008 -5.517896 270)
			(unlocked yes)
			(layer "B.Fab")
			(hide yes)
			(effects
				(font
					(size 1.016 1.016)
					(thickness 0.1524)
				)
				(justify mirror)
			)
		)
		(duplicate_pad_numbers_are_jumpers no)
		(fp_line
			(start -0.508 -0.9398)
			(end 0.508 -0.9398)
			(stroke
				(width 0.1524)
				(type default)
			)
			(layer "B.SilkS")
		)
		(fp_line
			(start 0.508 -0.9398)
			(end 0.508 0.9398)
			(stroke
				(width 0.1524)
				(type default)
			)
			(layer "B.SilkS")
		)
		(fp_rect
			(start 0.508 0.9398)
			(end -0.508 -0.9398)
			(stroke
				(width 0)
				(type default)
			)
			(fill no)
			(layer "B.CrtYd")
		)
		(fp_rect
			(start 0.508 0.9398)
			(end -0.508 -0.9398)
			(stroke
				(width 0)
				(type default)
			)
			(fill no)
			(layer "B.Fab")
		)
		(pad "1" smd custom
			(at 0 -0.4445 90)
			(size 0.1397 0.1397)
			(layers "B.Cu" "B.Mask" "B.Paste")
			(net "LPCRST0_N")
			(options
				(clearance outline)
				(anchor circle)
			)
			(primitives
				(gr_poly
					(pts
						(arc
							(start -0.1778 0.2794)
							(mid -0.249642 0.249642)
							(end -0.2794 0.1778)
						)
						(arc
							(start -0.2794 -0.1778)
							(mid -0.249642 -0.249642)
							(end -0.1778 -0.2794)
						)
						(arc
							(start 0.1778 -0.2794)
							(mid 0.249642 -0.249642)
							(end 0.2794 -0.1778)
						)
						(arc
							(start 0.2794 0.1778)
							(mid 0.249642 0.249642)
							(end 0.1778 0.2794)
						)
					)
					(width 0)
					(fill yes)
				)
			)
		)
		(pad "2" smd custom
			(at 0 0.4445 90)
			(size 0.1397 0.1397)
			(layers "B.Cu" "B.Mask" "B.Paste")
			(net "GND")
			(options
				(clearance outline)
				(anchor circle)
			)
			(primitives
				(gr_poly
					(pts
						(arc
							(start -0.1778 0.2794)
							(mid -0.249642 0.249642)
							(end -0.2794 0.1778)
						)
						(arc
							(start -0.2794 -0.1778)
							(mid -0.249642 -0.249642)
							(end -0.1778 -0.2794)
						)
						(arc
							(start 0.1778 -0.2794)
							(mid 0.249642 -0.249642)
							(end 0.2794 -0.1778)
						)
						(arc
							(start 0.2794 0.1778)
							(mid 0.249642 0.249642)
							(end 0.1778 0.2794)
						)
					)
					(width 0)
					(fill yes)
				)
			)
		)
	)
	(footprint ""
		(layer "B.Cu")
		(at 109.555534 -59.15152)
		(property "Reference" "STP151"
			(at 0 0 0)
			(layer "B.SilkS")
			(hide yes)
			(effects
				(font
					(size 1.27 1.27)
				)
				(justify mirror)
			)
		)
		(property "Value" "TPAD28"
			(at -0.0127 -1.8034 0)
			(unlocked yes)
			(layer "B.Fab")
			(hide yes)
			(effects
				(font
					(size 1.016 1.016)
					(thickness 0.1524)
				)
				(justify mirror)
			)
		)
		(property "Device Type" "TPAD28"
			(at -0.0127 -3.3274 0)
			(unlocked yes)
			(layer "B.Fab")
			(hide yes)
			(effects
				(font
					(size 1.016 1.016)
					(thickness 0.1524)
				)
				(justify mirror)
			)
		)
		(duplicate_pad_numbers_are_jumpers no)
		(fp_poly
			(pts
				(arc
					(start 0.3556 0)
					(mid -0.3556 0)
					(end 0.3556 0)
				)
			)
			(stroke
				(width 0)
				(type default)
			)
			(fill no)
			(layer "B.CrtYd")
		)
		(fp_poly
			(pts
				(arc
					(start 0.6096 0)
					(mid -0.6096 0)
					(end 0.6096 0)
				)
			)
			(stroke
				(width 0)
				(type default)
			)
			(fill no)
			(layer "B.Fab")
		)
		(pad "1" smd circle
			(at 0 0 180)
			(size 0.7112 0.7112)
			(layers "B.Cu" "B.Mask" "B.Paste")
			(net "XM_ADDR_0")
		)
	)
	(footprint ""
		(layer "B.Cu")
		(at 97.92716 -31.623)
		(property "Reference" "SC1296"
			(at 0 0 0)
			(layer "B.SilkS")
			(hide yes)
			(effects
				(font
					(size 1.27 1.27)
				)
				(justify mirror)
			)
		)
		(property "Value" "SCD22U6D3V1MX-1-GP"
			(at 2.8321 -1.7399 0)
			(unlocked yes)
			(layer "B.Fab")
			(hide yes)
			(effects
				(font
					(size 1.016 1.016)
					(thickness 0.1524)
				)
				(justify mirror)
			)
		)
		(property "Device Type" "C0201H13"
			(at 2.8321 -3.2639 0)
			(unlocked yes)
			(layer "B.Fab")
			(hide yes)
			(effects
				(font
					(size 1.016 1.016)
					(thickness 0.1524)
				)
				(justify mirror)
			)
		)
		(duplicate_pad_numbers_are_jumpers no)
		(fp_rect
			(start 0.2794 0.6477)
			(end -0.2794 -0.6477)
			(stroke
				(width 0)
				(type default)
			)
			(fill no)
			(layer "B.CrtYd")
		)
		(fp_rect
			(start 0.2794 0.6477)
			(end -0.2794 -0.6477)
			(stroke
				(width 0)
				(type default)
			)
			(fill no)
			(layer "B.Fab")
		)
		(pad "1" smd custom
			(at 0 -0.2794 180)
			(size 0.0762 0.0762)
			(layers "B.Cu" "B.Mask" "B.Paste")
			(net "PCIE_SAS_C_CPU_RX_P3")
			(options
				(clearance outline)
				(anchor circle)
			)
			(primitives
				(gr_poly
					(pts
						(arc
							(start 0.1524 0.127)
							(mid 0.137521 0.162921)
							(end 0.1016 0.1778)
						)
						(arc
							(start -0.1016 0.1778)
							(mid -0.137521 0.162921)
							(end -0.1524 0.127)
						)
						(arc
							(start -0.1524 -0.127)
							(mid -0.137521 -0.162921)
							(end -0.1016 -0.1778)
						)
						(arc
							(start 0.1016 -0.1778)
							(mid 0.137521 -0.162921)
							(end 0.1524 -0.127)
						)
					)
					(width 0)
					(fill yes)
				)
			)
		)
		(pad "2" smd custom
			(at 0 0.2794 180)
			(size 0.0762 0.0762)
			(layers "B.Cu" "B.Mask" "B.Paste")
			(net "PCIE_SAS_CPU_RX_P3")
			(options
				(clearance outline)
				(anchor circle)
			)
			(primitives
				(gr_poly
					(pts
						(arc
							(start 0.1524 0.127)
							(mid 0.137521 0.162921)
							(end 0.1016 0.1778)
						)
						(arc
							(start -0.1016 0.1778)
							(mid -0.137521 0.162921)
							(end -0.1524 0.127)
						)
						(arc
							(start -0.1524 -0.127)
							(mid -0.137521 -0.162921)
							(end -0.1016 -0.1778)
						)
						(arc
							(start 0.1016 -0.1778)
							(mid 0.137521 -0.162921)
							(end 0.1524 -0.127)
						)
					)
					(width 0)
					(fill yes)
				)
			)
		)
	)
	(footprint ""
		(layer "B.Cu")
		(at 127.01397 -99.822 90)
		(property "Reference" "SC1167"
			(at 0 0 90)
			(layer "B.SilkS")
			(hide yes)
			(effects
				(font
					(size 1.27 1.27)
				)
				(justify mirror)
			)
		)
		(property "Value" "SCD1U6D3V1KX-GP"
			(at 2.8321 -1.7399 90)
			(unlocked yes)
			(layer "B.Fab")
			(hide yes)
			(effects
				(font
					(size 1.016 1.016)
					(thickness 0.1524)
				)
				(justify mirror)
			)
		)
		(property "Device Type" "C0201H13"
			(at 2.8321 -3.2639 90)
			(unlocked yes)
			(layer "B.Fab")
			(hide yes)
			(effects
				(font
					(size 1.016 1.016)
					(thickness 0.1524)
				)
				(justify mirror)
			)
		)
		(duplicate_pad_numbers_are_jumpers no)
		(fp_rect
			(start 0.2794 0.6477)
			(end -0.2794 -0.6477)
			(stroke
				(width 0)
				(type default)
			)
			(fill no)
			(layer "B.CrtYd")
		)
		(fp_rect
			(start 0.2794 0.6477)
			(end -0.2794 -0.6477)
			(stroke
				(width 0)
				(type default)
			)
			(fill no)
			(layer "B.Fab")
		)
		(pad "1" smd custom
			(at 0 -0.2794 270)
			(size 0.0762 0.0762)
			(layers "B.Cu" "B.Mask" "B.Paste")
			(net "GB_VDDA")
			(options
				(clearance outline)
				(anchor circle)
			)
			(primitives
				(gr_poly
					(pts
						(arc
							(start 0.1524 0.127)
							(mid 0.137521 0.162921)
							(end 0.1016 0.1778)
						)
						(arc
							(start -0.1016 0.1778)
							(mid -0.137521 0.162921)
							(end -0.1524 0.127)
						)
						(arc
							(start -0.1524 -0.127)
							(mid -0.137521 -0.162921)
							(end -0.1016 -0.1778)
						)
						(arc
							(start 0.1016 -0.1778)
							(mid 0.137521 -0.162921)
							(end 0.1524 -0.127)
						)
					)
					(width 0)
					(fill yes)
				)
			)
		)
		(pad "2" smd custom
			(at 0 0.2794 270)
			(size 0.0762 0.0762)
			(layers "B.Cu" "B.Mask" "B.Paste")
			(net "GND")
			(options
				(clearance outline)
				(anchor circle)
			)
			(primitives
				(gr_poly
					(pts
						(arc
							(start 0.1524 0.127)
							(mid 0.137521 0.162921)
							(end 0.1016 0.1778)
						)
						(arc
							(start -0.1016 0.1778)
							(mid -0.137521 0.162921)
							(end -0.1524 0.127)
						)
						(arc
							(start -0.1524 -0.127)
							(mid -0.137521 -0.162921)
							(end -0.1016 -0.1778)
						)
						(arc
							(start 0.1016 -0.1778)
							(mid 0.137521 -0.162921)
							(end 0.1524 -0.127)
						)
					)
					(width 0)
					(fill yes)
				)
			)
		)
	)
	(footprint ""
		(layer "B.Cu")
		(at 108.18876 -38.9382 180)
		(property "Reference" "SR686"
			(at 0 0 0)
			(layer "B.SilkS")
			(hide yes)
			(effects
				(font
					(size 1.27 1.27)
				)
				(justify mirror)
			)
		)
		(property "Value" "10KR2F-2-GP"
			(at -0.064008 -3.993896 180)
			(unlocked yes)
			(layer "B.Fab")
			(hide yes)
			(effects
				(font
					(size 1.016 1.016)
					(thickness 0.1524)
				)
				(justify mirror)
			)
		)
		(property "Device Type" "R402H16"
			(at -0.064008 -5.517896 180)
			(unlocked yes)
			(layer "B.Fab")
			(hide yes)
			(effects
				(font
					(size 1.016 1.016)
					(thickness 0.1524)
				)
				(justify mirror)
			)
		)
		(duplicate_pad_numbers_are_jumpers no)
		(fp_line
			(start 0.508 -0.9398)
			(end 0.508 0.9398)
			(stroke
				(width 0.1524)
				(type default)
			)
			(layer "B.SilkS")
		)
		(fp_line
			(start -0.508 -0.9398)
			(end 0.508 -0.9398)
			(stroke
				(width 0.1524)
				(type default)
			)
			(layer "B.SilkS")
		)
		(fp_rect
			(start 0.508 0.9398)
			(end -0.508 -0.9398)
			(stroke
				(width 0)
				(type default)
			)
			(fill no)
			(layer "B.CrtYd")
		)
		(fp_rect
			(start 0.508 0.9398)
			(end -0.508 -0.9398)
			(stroke
				(width 0)
				(type default)
			)
			(fill no)
			(layer "B.Fab")
		)
		(pad "1" smd custom
			(at 0 -0.4445)
			(size 0.1397 0.1397)
			(layers "B.Cu" "B.Mask" "B.Paste")
			(net "SYS_DBMODE0")
			(options
				(clearance outline)
				(anchor circle)
			)
			(primitives
				(gr_poly
					(pts
						(arc
							(start -0.1778 0.2794)
							(mid -0.249642 0.249642)
							(end -0.2794 0.1778)
						)
						(arc
							(start -0.2794 -0.1778)
							(mid -0.249642 -0.249642)
							(end -0.1778 -0.2794)
						)
						(arc
							(start 0.1778 -0.2794)
							(mid 0.249642 -0.249642)
							(end 0.2794 -0.1778)
						)
						(arc
							(start 0.2794 0.1778)
							(mid 0.249642 0.249642)
							(end 0.1778 0.2794)
						)
					)
					(width 0)
					(fill yes)
				)
			)
		)
		(pad "2" smd custom
			(at 0 0.4445)
			(size 0.1397 0.1397)
			(layers "B.Cu" "B.Mask" "B.Paste")
			(net "GND")
			(options
				(clearance outline)
				(anchor circle)
			)
			(primitives
				(gr_poly
					(pts
						(arc
							(start -0.1778 0.2794)
							(mid -0.249642 0.249642)
							(end -0.2794 0.1778)
						)
						(arc
							(start -0.2794 -0.1778)
							(mid -0.249642 -0.249642)
							(end -0.1778 -0.2794)
						)
						(arc
							(start 0.1778 -0.2794)
							(mid 0.249642 -0.249642)
							(end 0.2794 -0.1778)
						)
						(arc
							(start 0.2794 0.1778)
							(mid 0.249642 0.249642)
							(end 0.1778 0.2794)
						)
					)
					(width 0)
					(fill yes)
				)
			)
		)
	)
	(footprint ""
		(layer "B.Cu")
		(at 318.008 -177.673 -90)
		(property "Reference" "R316"
			(at 0 0 90)
			(layer "B.SilkS")
			(hide yes)
			(effects
				(font
					(size 1.27 1.27)
				)
				(justify mirror)
			)
		)
		(property "Value" "0R2J-2-GP"
			(at -0.064008 -3.993896 270)
			(unlocked yes)
			(layer "B.Fab")
			(hide yes)
			(effects
				(font
					(size 1.016 1.016)
					(thickness 0.1524)
				)
				(justify mirror)
			)
		)
		(property "Device Type" "R402H16"
			(at -0.064008 -5.517896 270)
			(unlocked yes)
			(layer "B.Fab")
			(hide yes)
			(effects
				(font
					(size 1.016 1.016)
					(thickness 0.1524)
				)
				(justify mirror)
			)
		)
		(duplicate_pad_numbers_are_jumpers no)
		(fp_line
			(start -0.508 -0.9398)
			(end 0.508 -0.9398)
			(stroke
				(width 0.1524)
				(type default)
			)
			(layer "B.SilkS")
		)
		(fp_line
			(start 0.508 -0.9398)
			(end 0.508 0.9398)
			(stroke
				(width 0.1524)
				(type default)
			)
			(layer "B.SilkS")
		)
		(fp_rect
			(start 0.508 0.9398)
			(end -0.508 -0.9398)
			(stroke
				(width 0)
				(type default)
			)
			(fill no)
			(layer "B.CrtYd")
		)
		(fp_rect
			(start 0.508 0.9398)
			(end -0.508 -0.9398)
			(stroke
				(width 0)
				(type default)
			)
			(fill no)
			(layer "B.Fab")
		)
		(pad "1" smd custom
			(at 0 -0.4445 90)
			(size 0.1397 0.1397)
			(layers "B.Cu" "B.Mask" "B.Paste")
			(net "ADC_P5V_STBY")
			(options
				(clearance outline)
				(anchor circle)
			)
			(primitives
				(gr_poly
					(pts
						(arc
							(start -0.1778 0.2794)
							(mid -0.249642 0.249642)
							(end -0.2794 0.1778)
						)
						(arc
							(start -0.2794 -0.1778)
							(mid -0.249642 -0.249642)
							(end -0.1778 -0.2794)
						)
						(arc
							(start 0.1778 -0.2794)
							(mid 0.249642 -0.249642)
							(end 0.2794 -0.1778)
						)
						(arc
							(start 0.2794 0.1778)
							(mid 0.249642 0.249642)
							(end 0.1778 0.2794)
						)
					)
					(width 0)
					(fill yes)
				)
			)
		)
		(pad "2" smd custom
			(at 0 0.4445 90)
			(size 0.1397 0.1397)
			(layers "B.Cu" "B.Mask" "B.Paste")
			(net "ADC_P5V_STBY_BMC")
			(options
				(clearance outline)
				(anchor circle)
			)
			(primitives
				(gr_poly
					(pts
						(arc
							(start -0.1778 0.2794)
							(mid -0.249642 0.249642)
							(end -0.2794 0.1778)
						)
						(arc
							(start -0.2794 -0.1778)
							(mid -0.249642 -0.249642)
							(end -0.1778 -0.2794)
						)
						(arc
							(start 0.1778 -0.2794)
							(mid 0.249642 -0.249642)
							(end 0.2794 -0.1778)
						)
						(arc
							(start 0.2794 0.1778)
							(mid 0.249642 0.249642)
							(end 0.1778 0.2794)
						)
					)
					(width 0)
					(fill yes)
				)
			)
		)
	)
	(footprint ""
		(layer "B.Cu")
		(at 135.382 -37.719 90)
		(property "Reference" "SR660"
			(at 0 0 90)
			(layer "B.SilkS")
			(hide yes)
			(effects
				(font
					(size 1.27 1.27)
				)
				(justify mirror)
			)
		)
		(property "Value" "4K7R2F-GP"
			(at -0.064008 -3.993896 90)
			(unlocked yes)
			(layer "B.Fab")
			(hide yes)
			(effects
				(font
					(size 1.016 1.016)
					(thickness 0.1524)
				)
				(justify mirror)
			)
		)
		(property "Device Type" "R402H16"
			(at -0.064008 -5.517896 90)
			(unlocked yes)
			(layer "B.Fab")
			(hide yes)
			(effects
				(font
					(size 1.016 1.016)
					(thickness 0.1524)
				)
				(justify mirror)
			)
		)
		(duplicate_pad_numbers_are_jumpers no)
		(fp_line
			(start 0.508 -0.9398)
			(end 0.508 0.9398)
			(stroke
				(width 0.1524)
				(type default)
			)
			(layer "B.SilkS")
		)
		(fp_line
			(start -0.508 -0.9398)
			(end 0.508 -0.9398)
			(stroke
				(width 0.1524)
				(type default)
			)
			(layer "B.SilkS")
		)
		(fp_rect
			(start 0.508 0.9398)
			(end -0.508 -0.9398)
			(stroke
				(width 0)
				(type default)
			)
			(fill no)
			(layer "B.CrtYd")
		)
		(fp_rect
			(start 0.508 0.9398)
			(end -0.508 -0.9398)
			(stroke
				(width 0)
				(type default)
			)
			(fill no)
			(layer "B.Fab")
		)
		(pad "1" smd custom
			(at 0 -0.4445 270)
			(size 0.1397 0.1397)
			(layers "B.Cu" "B.Mask" "B.Paste")
			(net "PMU_PLTRST_R_N")
			(options
				(clearance outline)
				(anchor circle)
			)
			(primitives
				(gr_poly
					(pts
						(arc
							(start -0.1778 0.2794)
							(mid -0.249642 0.249642)
							(end -0.2794 0.1778)
						)
						(arc
							(start -0.2794 -0.1778)
							(mid -0.249642 -0.249642)
							(end -0.1778 -0.2794)
						)
						(arc
							(start 0.1778 -0.2794)
							(mid 0.249642 -0.249642)
							(end 0.2794 -0.1778)
						)
						(arc
							(start 0.2794 0.1778)
							(mid 0.249642 0.249642)
							(end 0.1778 0.2794)
						)
					)
					(width 0)
					(fill yes)
				)
			)
		)
		(pad "2" smd custom
			(at 0 0.4445 270)
			(size 0.1397 0.1397)
			(layers "B.Cu" "B.Mask" "B.Paste")
			(net "PMU_PLTRST_N")
			(options
				(clearance outline)
				(anchor circle)
			)
			(primitives
				(gr_poly
					(pts
						(arc
							(start -0.1778 0.2794)
							(mid -0.249642 0.249642)
							(end -0.2794 0.1778)
						)
						(arc
							(start -0.2794 -0.1778)
							(mid -0.249642 -0.249642)
							(end -0.1778 -0.2794)
						)
						(arc
							(start 0.1778 -0.2794)
							(mid 0.249642 -0.249642)
							(end 0.2794 -0.1778)
						)
						(arc
							(start 0.2794 0.1778)
							(mid 0.249642 0.249642)
							(end 0.1778 0.2794)
						)
					)
					(width 0)
					(fill yes)
				)
			)
		)
	)
)
